(kicad_pcb
	(version 20260206)
	(generator "pcbnew")
	(generator_version "10.0")
	(general
		(thickness 1.6)
		(legacy_teardrops no)
	)
	(paper "A4")
	(title_block
		(title "01162023_DA0F0TEBIF0_F0T_Expander_BD_F_brd_V02_OCP.brd")
		(comment 1 "Grand Teton / footprints 3561-3566 of 9728")
	)
	(layers
		(0 "F.Cu" signal "TOP")
		(4 "In1.Cu" signal "GND")
		(6 "In2.Cu" signal "VCC")
		(8 "In3.Cu" signal "VCC1")
		(10 "In4.Cu" signal "GND1")
		(12 "In5.Cu" signal "IN1")
		(14 "In6.Cu" signal "GND2")
		(16 "In7.Cu" signal "IN2")
		(18 "In8.Cu" signal "GND3")
		(20 "In9.Cu" signal "IN3")
		(22 "In10.Cu" signal "GND4")
		(24 "In11.Cu" signal "IN4")
		(26 "In12.Cu" signal "GND5")
		(28 "In13.Cu" signal "IN5")
		(30 "In14.Cu" signal "GND6")
		(32 "In15.Cu" signal "IN6")
		(34 "In16.Cu" signal "GND7")
		(2 "B.Cu" signal "BOTTOM")
		(9 "F.Adhes" user "F.Adhesive")
		(11 "B.Adhes" user "B.Adhesive")
		(13 "F.Paste" user "Package Geometry/Pastemask Top")
		(15 "B.Paste" user "Package Geometry/Pastemask Bottom")
		(5 "F.SilkS" user "Ref Des/Silkscreen Top")
		(7 "B.SilkS" user "Ref Des/Silkscreen Bottom")
		(1 "F.Mask" user "Board Geometry/Soldermask Top")
		(3 "B.Mask" user "Board Geometry/Soldermask Bottom")
		(17 "Dwgs.User" user "User.Drawings")
		(19 "Cmts.User" user "User.Comments")
		(21 "Eco1.User" user "User.Eco1")
		(23 "Eco2.User" user "User.Eco2")
		(25 "Edge.Cuts" user "Board Geometry/Outline")
		(27 "Margin" user)
		(31 "F.CrtYd" user "Package Geometry/Place Bound Top")
		(29 "B.CrtYd" user "Package Geometry/Place Bound Bottom")
		(35 "F.Fab" user "Ref Des/Assembly Top")
		(33 "B.Fab" user "Ref Des/Assembly Bottom")
	)
	(footprint ""
		(layer "F.Cu")
		(at 108.106464 -390.420352 180)
		(property "Reference" "R5455"
			(at 0 0 180)
			(layer "F.SilkS")
			(hide yes)
			(effects
				(font
					(size 1.27 1.27)
				)
			)
		)
		(property "Value" ""
			(at 0 0 180)
			(layer "F.Fab")
			(effects
				(font
					(size 1.27 1.27)
				)
			)
		)
		(duplicate_pad_numbers_are_jumpers no)
		(fp_line
			(start 0.7874 0.4064)
			(end -0.7874 0.4064)
			(stroke
				(width 0.1524)
				(type default)
			)
			(layer "F.SilkS")
		)
		(fp_line
			(start 0.7874 -0.4064)
			(end 0.7874 0.4064)
			(stroke
				(width 0.1524)
				(type default)
			)
			(layer "F.SilkS")
		)
		(fp_line
			(start -0.7874 0.4064)
			(end -0.7874 -0.4064)
			(stroke
				(width 0.1524)
				(type default)
			)
			(layer "F.SilkS")
		)
		(fp_line
			(start -0.7874 -0.4064)
			(end 0.7874 -0.4064)
			(stroke
				(width 0.1524)
				(type default)
			)
			(layer "F.SilkS")
		)
		(fp_line
			(start 0.67945 0.3048)
			(end 0.120396 0.3048)
			(stroke
				(width 0.1)
				(type default)
			)
			(layer "F.Fab")
		)
		(fp_line
			(start 0.67945 -0.3048)
			(end 0.67945 0.3048)
			(stroke
				(width 0.1)
				(type default)
			)
			(layer "F.Fab")
		)
		(fp_line
			(start 0.12065 -0.2794)
			(end 0.12065 -0.3048)
			(stroke
				(width 0.1)
				(type default)
			)
			(layer "F.Fab")
		)
		(fp_line
			(start 0.12065 -0.3048)
			(end 0.67945 -0.3048)
			(stroke
				(width 0.1)
				(type default)
			)
			(layer "F.Fab")
		)
		(fp_line
			(start 0.120396 0.3048)
			(end 0.120396 0.2794)
			(stroke
				(width 0.1)
				(type default)
			)
			(layer "F.Fab")
		)
		(fp_line
			(start 0.120396 0.2794)
			(end -0.12065 0.2794)
			(stroke
				(width 0.1)
				(type default)
			)
			(layer "F.Fab")
		)
		(fp_line
			(start -0.12065 0.3048)
			(end -0.67945 0.3048)
			(stroke
				(width 0.1)
				(type default)
			)
			(layer "F.Fab")
		)
		(fp_line
			(start -0.12065 0.2794)
			(end -0.12065 0.3048)
			(stroke
				(width 0.1)
				(type default)
			)
			(layer "F.Fab")
		)
		(fp_line
			(start -0.12065 -0.2794)
			(end 0.12065 -0.2794)
			(stroke
				(width 0.1)
				(type default)
			)
			(layer "F.Fab")
		)
		(fp_line
			(start -0.12065 -0.305054)
			(end -0.12065 -0.2794)
			(stroke
				(width 0.1)
				(type default)
			)
			(layer "F.Fab")
		)
		(fp_line
			(start -0.67945 0.3048)
			(end -0.67945 -0.305054)
			(stroke
				(width 0.1)
				(type default)
			)
			(layer "F.Fab")
		)
		(fp_line
			(start -0.67945 -0.305054)
			(end -0.12065 -0.305054)
			(stroke
				(width 0.1)
				(type default)
			)
			(layer "F.Fab")
		)
		(pad "1" smd circle
			(at -0.40005 0 180)
			(size 0 0)
			(layers "F.Cu" "F.Mask" "F.Paste")
			(net "GND")
		)
		(pad "2" smd circle
			(at 0.40005 0 180)
			(size 0 0)
			(layers "F.Cu" "F.Mask" "F.Paste")
			(net "BIC_USB_HUB_RREF")
		)
	)
	(footprint ""
		(layer "F.Cu")
		(at 400.325082 -14.735302 180)
		(property "Reference" "C2738"
			(at 0 0 180)
			(layer "F.SilkS")
			(hide yes)
			(effects
				(font
					(size 1.27 1.27)
				)
			)
		)
		(property "Value" ""
			(at 0 0 180)
			(layer "F.Fab")
			(effects
				(font
					(size 1.27 1.27)
				)
			)
		)
		(duplicate_pad_numbers_are_jumpers no)
		(fp_line
			(start 0.7874 0.4064)
			(end -0.7874 0.4064)
			(stroke
				(width 0.1524)
				(type default)
			)
			(layer "F.SilkS")
		)
		(fp_line
			(start 0.7874 -0.4064)
			(end 0.7874 0.4064)
			(stroke
				(width 0.1524)
				(type default)
			)
			(layer "F.SilkS")
		)
		(fp_line
			(start -0.7874 0.4064)
			(end -0.7874 -0.4064)
			(stroke
				(width 0.1524)
				(type default)
			)
			(layer "F.SilkS")
		)
		(fp_line
			(start -0.7874 -0.4064)
			(end 0.7874 -0.4064)
			(stroke
				(width 0.1524)
				(type default)
			)
			(layer "F.SilkS")
		)
		(fp_line
			(start 0.67945 0.3048)
			(end 0.120396 0.3048)
			(stroke
				(width 0.1)
				(type default)
			)
			(layer "F.Fab")
		)
		(fp_line
			(start 0.67945 -0.3048)
			(end 0.67945 0.3048)
			(stroke
				(width 0.1)
				(type default)
			)
			(layer "F.Fab")
		)
		(fp_line
			(start 0.12065 -0.2794)
			(end 0.12065 -0.3048)
			(stroke
				(width 0.1)
				(type default)
			)
			(layer "F.Fab")
		)
		(fp_line
			(start 0.12065 -0.3048)
			(end 0.67945 -0.3048)
			(stroke
				(width 0.1)
				(type default)
			)
			(layer "F.Fab")
		)
		(fp_line
			(start 0.120396 0.3048)
			(end 0.120396 0.2794)
			(stroke
				(width 0.1)
				(type default)
			)
			(layer "F.Fab")
		)
		(fp_line
			(start 0.120396 0.2794)
			(end -0.12065 0.2794)
			(stroke
				(width 0.1)
				(type default)
			)
			(layer "F.Fab")
		)
		(fp_line
			(start -0.12065 0.3048)
			(end -0.67945 0.3048)
			(stroke
				(width 0.1)
				(type default)
			)
			(layer "F.Fab")
		)
		(fp_line
			(start -0.12065 0.2794)
			(end -0.12065 0.3048)
			(stroke
				(width 0.1)
				(type default)
			)
			(layer "F.Fab")
		)
		(fp_line
			(start -0.12065 -0.2794)
			(end 0.12065 -0.2794)
			(stroke
				(width 0.1)
				(type default)
			)
			(layer "F.Fab")
		)
		(fp_line
			(start -0.12065 -0.305054)
			(end -0.12065 -0.2794)
			(stroke
				(width 0.1)
				(type default)
			)
			(layer "F.Fab")
		)
		(fp_line
			(start -0.67945 0.3048)
			(end -0.67945 -0.305054)
			(stroke
				(width 0.1)
				(type default)
			)
			(layer "F.Fab")
		)
		(fp_line
			(start -0.67945 -0.305054)
			(end -0.12065 -0.305054)
			(stroke
				(width 0.1)
				(type default)
			)
			(layer "F.Fab")
		)
		(pad "1" smd circle
			(at -0.40005 0 180)
			(size 0 0)
			(layers "F.Cu" "F.Mask" "F.Paste")
			(net "GND")
		)
		(pad "2" smd circle
			(at 0.40005 0 180)
			(size 0 0)
			(layers "F.Cu" "F.Mask" "F.Paste")
			(net "P3V3_SSD13")
		)
	)
	(footprint ""
		(layer "F.Cu")
		(at 369.495578 -89.499694 180)
		(property "Reference" "R1612"
			(at 0 0 180)
			(layer "F.SilkS")
			(hide yes)
			(effects
				(font
					(size 1.27 1.27)
				)
			)
		)
		(property "Value" ""
			(at 0 0 180)
			(layer "F.Fab")
			(effects
				(font
					(size 1.27 1.27)
				)
			)
		)
		(duplicate_pad_numbers_are_jumpers no)
		(fp_line
			(start 0.7874 0.4064)
			(end -0.7874 0.4064)
			(stroke
				(width 0.1524)
				(type default)
			)
			(layer "F.SilkS")
		)
		(fp_line
			(start 0.7874 -0.4064)
			(end 0.7874 0.4064)
			(stroke
				(width 0.1524)
				(type default)
			)
			(layer "F.SilkS")
		)
		(fp_line
			(start -0.7874 0.4064)
			(end -0.7874 -0.4064)
			(stroke
				(width 0.1524)
				(type default)
			)
			(layer "F.SilkS")
		)
		(fp_line
			(start -0.7874 -0.4064)
			(end 0.7874 -0.4064)
			(stroke
				(width 0.1524)
				(type default)
			)
			(layer "F.SilkS")
		)
		(fp_line
			(start 0.67945 0.3048)
			(end 0.120396 0.3048)
			(stroke
				(width 0.1)
				(type default)
			)
			(layer "F.Fab")
		)
		(fp_line
			(start 0.67945 -0.3048)
			(end 0.67945 0.3048)
			(stroke
				(width 0.1)
				(type default)
			)
			(layer "F.Fab")
		)
		(fp_line
			(start 0.12065 -0.2794)
			(end 0.12065 -0.3048)
			(stroke
				(width 0.1)
				(type default)
			)
			(layer "F.Fab")
		)
		(fp_line
			(start 0.12065 -0.3048)
			(end 0.67945 -0.3048)
			(stroke
				(width 0.1)
				(type default)
			)
			(layer "F.Fab")
		)
		(fp_line
			(start 0.120396 0.3048)
			(end 0.120396 0.2794)
			(stroke
				(width 0.1)
				(type default)
			)
			(layer "F.Fab")
		)
		(fp_line
			(start 0.120396 0.2794)
			(end -0.12065 0.2794)
			(stroke
				(width 0.1)
				(type default)
			)
			(layer "F.Fab")
		)
		(fp_line
			(start -0.12065 0.3048)
			(end -0.67945 0.3048)
			(stroke
				(width 0.1)
				(type default)
			)
			(layer "F.Fab")
		)
		(fp_line
			(start -0.12065 0.2794)
			(end -0.12065 0.3048)
			(stroke
				(width 0.1)
				(type default)
			)
			(layer "F.Fab")
		)
		(fp_line
			(start -0.12065 -0.2794)
			(end 0.12065 -0.2794)
			(stroke
				(width 0.1)
				(type default)
			)
			(layer "F.Fab")
		)
		(fp_line
			(start -0.12065 -0.305054)
			(end -0.12065 -0.2794)
			(stroke
				(width 0.1)
				(type default)
			)
			(layer "F.Fab")
		)
		(fp_line
			(start -0.67945 0.3048)
			(end -0.67945 -0.305054)
			(stroke
				(width 0.1)
				(type default)
			)
			(layer "F.Fab")
		)
		(fp_line
			(start -0.67945 -0.305054)
			(end -0.12065 -0.305054)
			(stroke
				(width 0.1)
				(type default)
			)
			(layer "F.Fab")
		)
		(pad "1" smd circle
			(at -0.40005 0 180)
			(size 0 0)
			(layers "F.Cu" "F.Mask" "F.Paste")
			(net "P3V3_AUX")
		)
		(pad "2" smd circle
			(at 0.40005 0 180)
			(size 0 0)
			(layers "F.Cu" "F.Mask" "F.Paste")
			(net "SMB_BIC_I2C9_MUX1_SSD15_R_SCL")
		)
	)
	(footprint ""
		(layer "F.Cu")
		(at 6.804406 -348.911926)
		(property "Reference" "H42"
			(at -2.808478 -3.424936 0)
			(unlocked yes)
			(layer "F.SilkS")
			(effects
				(font
					(size 0.7874 0.5842)
					(thickness 0.1524)
				)
				(justify left)
			)
		)
		(property "Value" ""
			(at 0 0 0)
			(layer "F.Fab")
			(effects
				(font
					(size 1.27 1.27)
				)
			)
		)
		(duplicate_pad_numbers_are_jumpers no)
		(fp_circle
			(center 0 0)
			(end 2.4003 0)
			(stroke
				(width 0.1524)
				(type default)
			)
			(fill no)
			(layer "F.SilkS")
		)
		(fp_circle
			(center 0 0)
			(end 6.5913 0)
			(stroke
				(width 0.1524)
				(type default)
			)
			(fill no)
			(layer "B.SilkS")
		)
		(fp_circle
			(center 0 0)
			(end 6.5913 0)
			(stroke
				(width 0.1)
				(type default)
			)
			(fill no)
			(layer "B.Fab")
		)
		(fp_circle
			(center 0 0)
			(end 2.4003 0)
			(stroke
				(width 0.1)
				(type default)
			)
			(fill no)
			(layer "F.Fab")
		)
		(pad "" np_thru_hole circle
			(at 0 0)
			(size 3.175 3.175)
			(drill 3.175)
			(layers "*.Cu" "*.Mask")
			(clearance 0.381)
			(thermal_gap 0.381)
		)
		(zone
			(layers "F.Cu" "B.Cu" "In1.Cu" "In2.Cu" "In3.Cu" "In4.Cu" "In5.Cu" "In6.Cu"
				"In7.Cu" "In8.Cu" "In9.Cu" "In10.Cu" "In11.Cu" "In12.Cu" "In13.Cu" "In14.Cu"
				"In15.Cu" "In16.Cu"
			)
			(hatch none 0.5)
			(connect_pads
				(clearance 0)
			)
			(min_thickness 0.25)
			(keepout
				(tracks not_allowed)
				(vias allowed)
				(pads allowed)
				(copperpour not_allowed)
				(footprints allowed)
			)
			(placement
				(enabled no)
				(sheetname "")
			)
			(fill
				(thermal_gap 0.5)
				(thermal_bridge_width 0.5)
				(island_removal_mode 0)
			)
			(polygon
				(pts
					(arc
						(start 8.899906 -348.911926)
						(mid 4.708906 -348.911926)
						(end 8.899906 -348.911926)
					)
				)
			)
		)
	)
	(footprint ""
		(layer "F.Cu")
		(at 303.457864 -72.766682 90)
		(property "Reference" "PC870"
			(at 0 0 90)
			(layer "F.SilkS")
			(hide yes)
			(effects
				(font
					(size 1.27 1.27)
				)
			)
		)
		(property "Value" ""
			(at 0 0 90)
			(layer "F.Fab")
			(effects
				(font
					(size 1.27 1.27)
				)
			)
		)
		(duplicate_pad_numbers_are_jumpers no)
		(fp_line
			(start 0.7874 -0.4064)
			(end 0.7874 0.4064)
			(stroke
				(width 0.1524)
				(type default)
			)
			(layer "F.SilkS")
		)
		(fp_line
			(start -0.7874 -0.4064)
			(end 0.7874 -0.4064)
			(stroke
				(width 0.1524)
				(type default)
			)
			(layer "F.SilkS")
		)
		(fp_line
			(start 0.7874 0.4064)
			(end -0.7874 0.4064)
			(stroke
				(width 0.1524)
				(type default)
			)
			(layer "F.SilkS")
		)
		(fp_line
			(start -0.7874 0.4064)
			(end -0.7874 -0.4064)
			(stroke
				(width 0.1524)
				(type default)
			)
			(layer "F.SilkS")
		)
		(fp_line
			(start -0.12065 -0.305054)
			(end -0.12065 -0.2794)
			(stroke
				(width 0.1)
				(type default)
			)
			(layer "F.Fab")
		)
		(fp_line
			(start -0.67945 -0.305054)
			(end -0.12065 -0.305054)
			(stroke
				(width 0.1)
				(type default)
			)
			(layer "F.Fab")
		)
		(fp_line
			(start 0.67945 -0.3048)
			(end 0.67945 0.3048)
			(stroke
				(width 0.1)
				(type default)
			)
			(layer "F.Fab")
		)
		(fp_line
			(start 0.12065 -0.3048)
			(end 0.67945 -0.3048)
			(stroke
				(width 0.1)
				(type default)
			)
			(layer "F.Fab")
		)
		(fp_line
			(start 0.12065 -0.2794)
			(end 0.12065 -0.3048)
			(stroke
				(width 0.1)
				(type default)
			)
			(layer "F.Fab")
		)
		(fp_line
			(start -0.12065 -0.2794)
			(end 0.12065 -0.2794)
			(stroke
				(width 0.1)
				(type default)
			)
			(layer "F.Fab")
		)
		(fp_line
			(start 0.120396 0.2794)
			(end -0.12065 0.2794)
			(stroke
				(width 0.1)
				(type default)
			)
			(layer "F.Fab")
		)
		(fp_line
			(start -0.12065 0.2794)
			(end -0.12065 0.3048)
			(stroke
				(width 0.1)
				(type default)
			)
			(layer "F.Fab")
		)
		(fp_line
			(start 0.67945 0.3048)
			(end 0.120396 0.3048)
			(stroke
				(width 0.1)
				(type default)
			)
			(layer "F.Fab")
		)
		(fp_line
			(start 0.120396 0.3048)
			(end 0.120396 0.2794)
			(stroke
				(width 0.1)
				(type default)
			)
			(layer "F.Fab")
		)
		(fp_line
			(start -0.12065 0.3048)
			(end -0.67945 0.3048)
			(stroke
				(width 0.1)
				(type default)
			)
			(layer "F.Fab")
		)
		(fp_line
			(start -0.67945 0.3048)
			(end -0.67945 -0.305054)
			(stroke
				(width 0.1)
				(type default)
			)
			(layer "F.Fab")
		)
		(pad "1" smd circle
			(at -0.40005 0 90)
			(size 0 0)
			(layers "F.Cu" "F.Mask" "F.Paste")
			(net "P12V_SSD10_CO_MODE")
		)
		(pad "2" smd circle
			(at 0.40005 0 90)
			(size 0 0)
			(layers "F.Cu" "F.Mask" "F.Paste")
			(net "GND")
		)
	)
	(footprint ""
		(layer "F.Cu")
		(at 62.632082 -169.040302 -90)
		(property "Reference" "U12"
			(at 0.50038 2.571242 90)
			(unlocked yes)
			(layer "F.SilkS")
			(effects
				(font
					(size 0.7874 0.5842)
					(thickness 0.1524)
				)
			)
		)
		(property "Value" ""
			(at 0 0 270)
			(layer "F.Fab")
			(effects
				(font
					(size 1.27 1.27)
				)
			)
		)
		(duplicate_pad_numbers_are_jumpers no)
		(fp_line
			(start -1.905 1.651)
			(end -1.905 -1.651)
			(stroke
				(width 0.1524)
				(type default)
			)
			(layer "F.SilkS")
		)
		(fp_line
			(start 1.905 1.651)
			(end -1.905 1.651)
			(stroke
				(width 0.1524)
				(type default)
			)
			(layer "F.SilkS")
		)
		(fp_line
			(start -1.905 -1.651)
			(end 1.905 -1.651)
			(stroke
				(width 0.1524)
				(type default)
			)
			(layer "F.SilkS")
		)
		(fp_line
			(start 1.905 -1.651)
			(end 1.905 1.651)
			(stroke
				(width 0.1524)
				(type default)
			)
			(layer "F.SilkS")
		)
		(fp_line
			(start -0.649986 1.524)
			(end -0.649986 1.169924)
			(stroke
				(width 0.1)
				(type default)
			)
			(layer "F.Fab")
		)
		(fp_line
			(start 0.6985 1.524)
			(end -0.649986 1.524)
			(stroke
				(width 0.1)
				(type default)
			)
			(layer "F.Fab")
		)
		(fp_line
			(start -1.249934 1.169924)
			(end -1.249934 0.729996)
			(stroke
				(width 0.1)
				(type default)
			)
			(layer "F.Fab")
		)
		(fp_line
			(start -0.649986 1.169924)
			(end -1.249934 1.169924)
			(stroke
				(width 0.1)
				(type default)
			)
			(layer "F.Fab")
		)
		(fp_line
			(start -1.249934 0.729996)
			(end -0.6985 0.729996)
			(stroke
				(width 0.1)
				(type default)
			)
			(layer "F.Fab")
		)
		(fp_line
			(start -0.6985 0.729996)
			(end -0.6985 -0.729996)
			(stroke
				(width 0.1)
				(type default)
			)
			(layer "F.Fab")
		)
		(fp_line
			(start 0.6985 0.219964)
			(end 0.6985 1.524)
			(stroke
				(width 0.1)
				(type default)
			)
			(layer "F.Fab")
		)
		(fp_line
			(start 1.249934 0.219964)
			(end 0.6985 0.219964)
			(stroke
				(width 0.1)
				(type default)
			)
			(layer "F.Fab")
		)
		(fp_line
			(start 0.6985 -0.219964)
			(end 1.249934 -0.219964)
			(stroke
				(width 0.1)
				(type default)
			)
			(layer "F.Fab")
		)
		(fp_line
			(start 1.249934 -0.219964)
			(end 1.249934 0.219964)
			(stroke
				(width 0.1)
				(type default)
			)
			(layer "F.Fab")
		)
		(fp_line
			(start -1.249934 -0.729996)
			(end -1.249934 -1.169924)
			(stroke
				(width 0.1)
				(type default)
			)
			(layer "F.Fab")
		)
		(fp_line
			(start -0.6985 -0.729996)
			(end -1.249934 -0.729996)
			(stroke
				(width 0.1)
				(type default)
			)
			(layer "F.Fab")
		)
		(fp_line
			(start -1.249934 -1.169924)
			(end -0.649986 -1.169924)
			(stroke
				(width 0.1)
				(type default)
			)
			(layer "F.Fab")
		)
		(fp_line
			(start -0.649986 -1.169924)
			(end -0.649986 -1.524)
			(stroke
				(width 0.1)
				(type default)
			)
			(layer "F.Fab")
		)
		(fp_line
			(start -0.649986 -1.524)
			(end 0.6985 -1.524)
			(stroke
				(width 0.1)
				(type default)
			)
			(layer "F.Fab")
		)
		(fp_line
			(start 0.6985 -1.524)
			(end 0.6985 -0.219964)
			(stroke
				(width 0.1)
				(type default)
			)
			(layer "F.Fab")
		)
		(pad "1" smd rect
			(at -1.1176 -1.016 180)
			(size 1.016 1.27)
			(layers "F.Cu" "F.Mask" "F.Paste")
			(net "HP_NIC0_PWRGD")
		)
		(pad "2" smd rect
			(at -1.1176 1.016 180)
			(size 1.016 1.27)
			(layers "F.Cu" "F.Mask" "F.Paste")
			(net "P3V3_NIC0")
		)
		(pad "3" smd rect
			(at 1.1176 0 180)
			(size 1.016 1.27)
			(layers "F.Cu" "F.Mask" "F.Paste")
			(net "GND")
		)
	)
)
